(kicad_pcb
	(version 20260206)
	(generator "pcbnew")
	(generator_version "10.0")
	(general
		(thickness 1.6)
		(legacy_teardrops no)
	)
	(paper "A4")
	(title_block
		(title "03242023_DA0F0TMBIJ0_F0T_Motherboard_J_brd_V01_OCP.brd")
		(comment 1 "Grand Teton / footprints 4198-4205 of 6105")
	)
	(layers
		(0 "F.Cu" signal "TOP")
		(4 "In1.Cu" signal "GND")
		(6 "In2.Cu" signal "IN1")
		(8 "In3.Cu" signal "GND1")
		(10 "In4.Cu" signal "IN2")
		(12 "In5.Cu" signal "GND2")
		(14 "In6.Cu" signal "IN3")
		(16 "In7.Cu" signal "GND3")
		(18 "In8.Cu" signal "VCC")
		(20 "In9.Cu" signal "VCC1")
		(22 "In10.Cu" signal "GND4")
		(24 "In11.Cu" signal "IN4")
		(26 "In12.Cu" signal "GND5")
		(28 "In13.Cu" signal "IN5")
		(30 "In14.Cu" signal "GND6")
		(32 "In15.Cu" signal "IN6")
		(34 "In16.Cu" signal "GND7")
		(2 "B.Cu" signal "BOTTOM")
		(9 "F.Adhes" user "F.Adhesive")
		(11 "B.Adhes" user "B.Adhesive")
		(13 "F.Paste" user "Package Geometry/Pastemask Top")
		(15 "B.Paste" user "Package Geometry/Pastemask Bottom")
		(5 "F.SilkS" user "Ref Des/Silkscreen Top")
		(7 "B.SilkS" user "Ref Des/Silkscreen Bottom")
		(1 "F.Mask" user "Board Geometry/Soldermask Top")
		(3 "B.Mask" user "Board Geometry/Soldermask Bottom")
		(17 "Dwgs.User" user "User.Drawings")
		(19 "Cmts.User" user "User.Comments")
		(21 "Eco1.User" user "User.Eco1")
		(23 "Eco2.User" user "User.Eco2")
		(25 "Edge.Cuts" user "Board Geometry/Outline")
		(27 "Margin" user)
		(31 "F.CrtYd" user "Package Geometry/Place Bound Top")
		(29 "B.CrtYd" user "Package Geometry/Place Bound Bottom")
		(35 "F.Fab" user "Ref Des/Assembly Top")
		(33 "B.Fab" user "Ref Des/Assembly Bottom")
	)
	(footprint ""
		(layer "B.Cu")
		(at 351.841308 -244.820186 -90)
		(property "Reference" "C397"
			(at 0 0 90)
			(layer "B.SilkS")
			(hide yes)
			(effects
				(font
					(size 1.27 1.27)
				)
				(justify mirror)
			)
		)
		(property "Value" ""
			(at 0 0 90)
			(layer "B.Fab")
			(effects
				(font
					(size 1.27 1.27)
				)
				(justify mirror)
			)
		)
		(duplicate_pad_numbers_are_jumpers no)
		(fp_line
			(start -1.524 0.762)
			(end 1.524 0.762)
			(stroke
				(width 0.1524)
				(type default)
			)
			(layer "B.SilkS")
		)
		(fp_line
			(start 1.524 0.762)
			(end 1.524 -0.762)
			(stroke
				(width 0.1524)
				(type default)
			)
			(layer "B.SilkS")
		)
		(fp_line
			(start -1.524 -0.762)
			(end -1.524 0.762)
			(stroke
				(width 0.1524)
				(type default)
			)
			(layer "B.SilkS")
		)
		(fp_line
			(start 1.524 -0.762)
			(end -1.524 -0.762)
			(stroke
				(width 0.1524)
				(type default)
			)
			(layer "B.SilkS")
		)
		(fp_line
			(start -1.1049 0.724916)
			(end -1.1049 -0.724916)
			(stroke
				(width 0.1)
				(type default)
			)
			(layer "B.Fab")
		)
		(fp_line
			(start 1.1049 0.724916)
			(end -1.1049 0.724916)
			(stroke
				(width 0.1)
				(type default)
			)
			(layer "B.Fab")
		)
		(fp_line
			(start -1.1049 -0.724916)
			(end 1.1049 -0.724916)
			(stroke
				(width 0.1)
				(type default)
			)
			(layer "B.Fab")
		)
		(fp_line
			(start 1.1049 -0.724916)
			(end 1.1049 0.724916)
			(stroke
				(width 0.1)
				(type default)
			)
			(layer "B.Fab")
		)
		(pad "1" smd rect
			(at 0.889 0 270)
			(size 1.016 1.27)
			(layers "B.Cu" "B.Mask" "B.Paste")
			(net "PVCCIN_CPU0")
		)
		(pad "2" smd rect
			(at -0.889 0 270)
			(size 1.016 1.27)
			(layers "B.Cu" "B.Mask" "B.Paste")
			(net "GND")
		)
	)
	(footprint ""
		(layer "B.Cu")
		(at 36.12896 -319.519808 180)
		(property "Reference" "R2495"
			(at 0 0 0)
			(layer "B.SilkS")
			(hide yes)
			(effects
				(font
					(size 1.27 1.27)
				)
				(justify mirror)
			)
		)
		(property "Value" ""
			(at 0 0 0)
			(layer "B.Fab")
			(effects
				(font
					(size 1.27 1.27)
				)
				(justify mirror)
			)
		)
		(duplicate_pad_numbers_are_jumpers no)
		(fp_line
			(start 0.7874 0.4064)
			(end 0.7874 -0.4064)
			(stroke
				(width 0.1524)
				(type default)
			)
			(layer "B.SilkS")
		)
		(fp_line
			(start 0.7874 -0.4064)
			(end -0.7874 -0.4064)
			(stroke
				(width 0.1524)
				(type default)
			)
			(layer "B.SilkS")
		)
		(fp_line
			(start -0.7874 0.4064)
			(end 0.7874 0.4064)
			(stroke
				(width 0.1524)
				(type default)
			)
			(layer "B.SilkS")
		)
		(fp_line
			(start -0.7874 -0.4064)
			(end -0.7874 0.4064)
			(stroke
				(width 0.1524)
				(type default)
			)
			(layer "B.SilkS")
		)
		(fp_line
			(start 0.67945 0.3048)
			(end 0.67945 -0.305054)
			(stroke
				(width 0.1)
				(type default)
			)
			(layer "B.Fab")
		)
		(fp_line
			(start 0.67945 -0.305054)
			(end 0.12065 -0.305054)
			(stroke
				(width 0.1)
				(type default)
			)
			(layer "B.Fab")
		)
		(fp_line
			(start 0.12065 0.3048)
			(end 0.67945 0.3048)
			(stroke
				(width 0.1)
				(type default)
			)
			(layer "B.Fab")
		)
		(fp_line
			(start 0.12065 0.2794)
			(end 0.12065 0.3048)
			(stroke
				(width 0.1)
				(type default)
			)
			(layer "B.Fab")
		)
		(fp_line
			(start 0.12065 -0.2794)
			(end -0.12065 -0.2794)
			(stroke
				(width 0.1)
				(type default)
			)
			(layer "B.Fab")
		)
		(fp_line
			(start 0.12065 -0.305054)
			(end 0.12065 -0.2794)
			(stroke
				(width 0.1)
				(type default)
			)
			(layer "B.Fab")
		)
		(fp_line
			(start -0.120396 0.3048)
			(end -0.120396 0.2794)
			(stroke
				(width 0.1)
				(type default)
			)
			(layer "B.Fab")
		)
		(fp_line
			(start -0.120396 0.2794)
			(end 0.12065 0.2794)
			(stroke
				(width 0.1)
				(type default)
			)
			(layer "B.Fab")
		)
		(fp_line
			(start -0.12065 -0.2794)
			(end -0.12065 -0.3048)
			(stroke
				(width 0.1)
				(type default)
			)
			(layer "B.Fab")
		)
		(fp_line
			(start -0.12065 -0.3048)
			(end -0.67945 -0.3048)
			(stroke
				(width 0.1)
				(type default)
			)
			(layer "B.Fab")
		)
		(fp_line
			(start -0.67945 0.3048)
			(end -0.120396 0.3048)
			(stroke
				(width 0.1)
				(type default)
			)
			(layer "B.Fab")
		)
		(fp_line
			(start -0.67945 -0.3048)
			(end -0.67945 0.3048)
			(stroke
				(width 0.1)
				(type default)
			)
			(layer "B.Fab")
		)
		(pad "1" smd circle
			(at 0.40005 0)
			(size 0 0)
			(layers "B.Cu" "B.Mask" "B.Paste")
			(net "PWRGD_FAIL_CPU1_CD")
		)
		(pad "2" smd circle
			(at -0.40005 0)
			(size 0 0)
			(layers "B.Cu" "B.Mask" "B.Paste")
			(net "PWRGD_FAIL_CPU1_CD_R1")
		)
	)
	(footprint ""
		(layer "B.Cu")
		(at 30.784546 -319.268856 180)
		(property "Reference" "C65"
			(at 0 0 0)
			(layer "B.SilkS")
			(hide yes)
			(effects
				(font
					(size 1.27 1.27)
				)
				(justify mirror)
			)
		)
		(property "Value" ""
			(at 0 0 0)
			(layer "B.Fab")
			(effects
				(font
					(size 1.27 1.27)
				)
				(justify mirror)
			)
		)
		(duplicate_pad_numbers_are_jumpers no)
		(fp_line
			(start 0.7874 0.4064)
			(end 0.7874 -0.4064)
			(stroke
				(width 0.1524)
				(type default)
			)
			(layer "B.SilkS")
		)
		(fp_line
			(start 0.7874 -0.4064)
			(end -0.7874 -0.4064)
			(stroke
				(width 0.1524)
				(type default)
			)
			(layer "B.SilkS")
		)
		(fp_line
			(start -0.7874 0.4064)
			(end 0.7874 0.4064)
			(stroke
				(width 0.1524)
				(type default)
			)
			(layer "B.SilkS")
		)
		(fp_line
			(start -0.7874 -0.4064)
			(end -0.7874 0.4064)
			(stroke
				(width 0.1524)
				(type default)
			)
			(layer "B.SilkS")
		)
		(fp_line
			(start 0.67945 0.3048)
			(end 0.67945 -0.305054)
			(stroke
				(width 0.1)
				(type default)
			)
			(layer "B.Fab")
		)
		(fp_line
			(start 0.67945 -0.305054)
			(end 0.12065 -0.305054)
			(stroke
				(width 0.1)
				(type default)
			)
			(layer "B.Fab")
		)
		(fp_line
			(start 0.12065 0.3048)
			(end 0.67945 0.3048)
			(stroke
				(width 0.1)
				(type default)
			)
			(layer "B.Fab")
		)
		(fp_line
			(start 0.12065 0.2794)
			(end 0.12065 0.3048)
			(stroke
				(width 0.1)
				(type default)
			)
			(layer "B.Fab")
		)
		(fp_line
			(start 0.12065 -0.2794)
			(end -0.12065 -0.2794)
			(stroke
				(width 0.1)
				(type default)
			)
			(layer "B.Fab")
		)
		(fp_line
			(start 0.12065 -0.305054)
			(end 0.12065 -0.2794)
			(stroke
				(width 0.1)
				(type default)
			)
			(layer "B.Fab")
		)
		(fp_line
			(start -0.120396 0.3048)
			(end -0.120396 0.2794)
			(stroke
				(width 0.1)
				(type default)
			)
			(layer "B.Fab")
		)
		(fp_line
			(start -0.120396 0.2794)
			(end 0.12065 0.2794)
			(stroke
				(width 0.1)
				(type default)
			)
			(layer "B.Fab")
		)
		(fp_line
			(start -0.12065 -0.2794)
			(end -0.12065 -0.3048)
			(stroke
				(width 0.1)
				(type default)
			)
			(layer "B.Fab")
		)
		(fp_line
			(start -0.12065 -0.3048)
			(end -0.67945 -0.3048)
			(stroke
				(width 0.1)
				(type default)
			)
			(layer "B.Fab")
		)
		(fp_line
			(start -0.67945 0.3048)
			(end -0.120396 0.3048)
			(stroke
				(width 0.1)
				(type default)
			)
			(layer "B.Fab")
		)
		(fp_line
			(start -0.67945 -0.3048)
			(end -0.67945 0.3048)
			(stroke
				(width 0.1)
				(type default)
			)
			(layer "B.Fab")
		)
		(pad "1" smd circle
			(at 0.40005 0)
			(size 0 0)
			(layers "B.Cu" "B.Mask" "B.Paste")
			(net "P3V3_AUX")
		)
		(pad "2" smd circle
			(at -0.40005 0)
			(size 0 0)
			(layers "B.Cu" "B.Mask" "B.Paste")
			(net "GND")
		)
	)
	(footprint ""
		(layer "B.Cu")
		(at 407.91257 -174.140368 180)
		(property "Reference" "PC202_P0_1"
			(at 0 0 0)
			(layer "B.SilkS")
			(hide yes)
			(effects
				(font
					(size 1.27 1.27)
				)
				(justify mirror)
			)
		)
		(property "Value" ""
			(at 0 0 0)
			(layer "B.Fab")
			(effects
				(font
					(size 1.27 1.27)
				)
				(justify mirror)
			)
		)
		(duplicate_pad_numbers_are_jumpers no)
		(fp_line
			(start 1.524 0.762)
			(end 1.524 -0.762)
			(stroke
				(width 0.1524)
				(type default)
			)
			(layer "B.SilkS")
		)
		(fp_line
			(start 1.524 -0.762)
			(end -1.524 -0.762)
			(stroke
				(width 0.1524)
				(type default)
			)
			(layer "B.SilkS")
		)
		(fp_line
			(start -1.524 0.762)
			(end 1.524 0.762)
			(stroke
				(width 0.1524)
				(type default)
			)
			(layer "B.SilkS")
		)
		(fp_line
			(start -1.524 -0.762)
			(end -1.524 0.762)
			(stroke
				(width 0.1524)
				(type default)
			)
			(layer "B.SilkS")
		)
		(fp_line
			(start 1.1049 0.724916)
			(end -1.1049 0.724916)
			(stroke
				(width 0.1)
				(type default)
			)
			(layer "B.Fab")
		)
		(fp_line
			(start 1.1049 -0.724916)
			(end 1.1049 0.724916)
			(stroke
				(width 0.1)
				(type default)
			)
			(layer "B.Fab")
		)
		(fp_line
			(start -1.1049 0.724916)
			(end -1.1049 -0.724916)
			(stroke
				(width 0.1)
				(type default)
			)
			(layer "B.Fab")
		)
		(fp_line
			(start -1.1049 -0.724916)
			(end 1.1049 -0.724916)
			(stroke
				(width 0.1)
				(type default)
			)
			(layer "B.Fab")
		)
		(pad "1" smd rect
			(at 0.889 0 180)
			(size 1.016 1.27)
			(layers "B.Cu" "B.Mask" "B.Paste")
			(net "PVCCINFAON_CPU0")
		)
		(pad "2" smd rect
			(at -0.889 0 180)
			(size 1.016 1.27)
			(layers "B.Cu" "B.Mask" "B.Paste")
			(net "GND")
		)
	)
	(footprint ""
		(layer "B.Cu")
		(at 324.35292 -333.566008 -90)
		(property "Reference" "PR527"
			(at 0 0 90)
			(layer "B.SilkS")
			(hide yes)
			(effects
				(font
					(size 1.27 1.27)
				)
				(justify mirror)
			)
		)
		(property "Value" ""
			(at 0 0 90)
			(layer "B.Fab")
			(effects
				(font
					(size 1.27 1.27)
				)
				(justify mirror)
			)
		)
		(duplicate_pad_numbers_are_jumpers no)
		(fp_line
			(start -0.7874 0.4064)
			(end 0.7874 0.4064)
			(stroke
				(width 0.1524)
				(type default)
			)
			(layer "B.SilkS")
		)
		(fp_line
			(start 0.7874 0.4064)
			(end 0.7874 -0.4064)
			(stroke
				(width 0.1524)
				(type default)
			)
			(layer "B.SilkS")
		)
		(fp_line
			(start -0.7874 -0.4064)
			(end -0.7874 0.4064)
			(stroke
				(width 0.1524)
				(type default)
			)
			(layer "B.SilkS")
		)
		(fp_line
			(start 0.7874 -0.4064)
			(end -0.7874 -0.4064)
			(stroke
				(width 0.1524)
				(type default)
			)
			(layer "B.SilkS")
		)
		(fp_line
			(start -0.67945 0.3048)
			(end -0.120396 0.3048)
			(stroke
				(width 0.1)
				(type default)
			)
			(layer "B.Fab")
		)
		(fp_line
			(start -0.120396 0.3048)
			(end -0.120396 0.2794)
			(stroke
				(width 0.1)
				(type default)
			)
			(layer "B.Fab")
		)
		(fp_line
			(start 0.12065 0.3048)
			(end 0.67945 0.3048)
			(stroke
				(width 0.1)
				(type default)
			)
			(layer "B.Fab")
		)
		(fp_line
			(start 0.67945 0.3048)
			(end 0.67945 -0.305054)
			(stroke
				(width 0.1)
				(type default)
			)
			(layer "B.Fab")
		)
		(fp_line
			(start -0.120396 0.2794)
			(end 0.12065 0.2794)
			(stroke
				(width 0.1)
				(type default)
			)
			(layer "B.Fab")
		)
		(fp_line
			(start 0.12065 0.2794)
			(end 0.12065 0.3048)
			(stroke
				(width 0.1)
				(type default)
			)
			(layer "B.Fab")
		)
		(fp_line
			(start -0.12065 -0.2794)
			(end -0.12065 -0.3048)
			(stroke
				(width 0.1)
				(type default)
			)
			(layer "B.Fab")
		)
		(fp_line
			(start 0.12065 -0.2794)
			(end -0.12065 -0.2794)
			(stroke
				(width 0.1)
				(type default)
			)
			(layer "B.Fab")
		)
		(fp_line
			(start -0.67945 -0.3048)
			(end -0.67945 0.3048)
			(stroke
				(width 0.1)
				(type default)
			)
			(layer "B.Fab")
		)
		(fp_line
			(start -0.12065 -0.3048)
			(end -0.67945 -0.3048)
			(stroke
				(width 0.1)
				(type default)
			)
			(layer "B.Fab")
		)
		(fp_line
			(start 0.12065 -0.305054)
			(end 0.12065 -0.2794)
			(stroke
				(width 0.1)
				(type default)
			)
			(layer "B.Fab")
		)
		(fp_line
			(start 0.67945 -0.305054)
			(end 0.12065 -0.305054)
			(stroke
				(width 0.1)
				(type default)
			)
			(layer "B.Fab")
		)
		(pad "1" smd circle
			(at 0.40005 0 90)
			(size 0 0)
			(layers "B.Cu" "B.Mask" "B.Paste")
			(net "VSENSE_PVCCIN_CPU0_DN")
		)
		(pad "2" smd circle
			(at -0.40005 0 90)
			(size 0 0)
			(layers "B.Cu" "B.Mask" "B.Paste")
			(net "GND")
		)
	)
	(footprint ""
		(layer "B.Cu")
		(at 351.841308 -255.853946 90)
		(property "Reference" "C492"
			(at 0 0 90)
			(layer "B.SilkS")
			(hide yes)
			(effects
				(font
					(size 1.27 1.27)
				)
				(justify mirror)
			)
		)
		(property "Value" ""
			(at 0 0 90)
			(layer "B.Fab")
			(effects
				(font
					(size 1.27 1.27)
				)
				(justify mirror)
			)
		)
		(duplicate_pad_numbers_are_jumpers no)
		(fp_line
			(start 1.524 -0.762)
			(end -1.524 -0.762)
			(stroke
				(width 0.1524)
				(type default)
			)
			(layer "B.SilkS")
		)
		(fp_line
			(start -1.524 -0.762)
			(end -1.524 0.762)
			(stroke
				(width 0.1524)
				(type default)
			)
			(layer "B.SilkS")
		)
		(fp_line
			(start 1.524 0.762)
			(end 1.524 -0.762)
			(stroke
				(width 0.1524)
				(type default)
			)
			(layer "B.SilkS")
		)
		(fp_line
			(start -1.524 0.762)
			(end 1.524 0.762)
			(stroke
				(width 0.1524)
				(type default)
			)
			(layer "B.SilkS")
		)
		(fp_line
			(start 1.1049 -0.724916)
			(end 1.1049 0.724916)
			(stroke
				(width 0.1)
				(type default)
			)
			(layer "B.Fab")
		)
		(fp_line
			(start -1.1049 -0.724916)
			(end 1.1049 -0.724916)
			(stroke
				(width 0.1)
				(type default)
			)
			(layer "B.Fab")
		)
		(fp_line
			(start 1.1049 0.724916)
			(end -1.1049 0.724916)
			(stroke
				(width 0.1)
				(type default)
			)
			(layer "B.Fab")
		)
		(fp_line
			(start -1.1049 0.724916)
			(end -1.1049 -0.724916)
			(stroke
				(width 0.1)
				(type default)
			)
			(layer "B.Fab")
		)
		(pad "1" smd rect
			(at 0.889 0 90)
			(size 1.016 1.27)
			(layers "B.Cu" "B.Mask" "B.Paste")
			(net "PVCCFA_EHV_CPU0")
		)
		(pad "2" smd rect
			(at -0.889 0 90)
			(size 1.016 1.27)
			(layers "B.Cu" "B.Mask" "B.Paste")
			(net "GND")
		)
	)
	(footprint ""
		(layer "B.Cu")
		(at 53.415946 -319.268856 180)
		(property "Reference" "C50"
			(at 0 0 0)
			(layer "B.SilkS")
			(hide yes)
			(effects
				(font
					(size 1.27 1.27)
				)
				(justify mirror)
			)
		)
		(property "Value" ""
			(at 0 0 0)
			(layer "B.Fab")
			(effects
				(font
					(size 1.27 1.27)
				)
				(justify mirror)
			)
		)
		(duplicate_pad_numbers_are_jumpers no)
		(fp_line
			(start 0.7874 0.4064)
			(end 0.7874 -0.4064)
			(stroke
				(width 0.1524)
				(type default)
			)
			(layer "B.SilkS")
		)
		(fp_line
			(start 0.7874 -0.4064)
			(end -0.7874 -0.4064)
			(stroke
				(width 0.1524)
				(type default)
			)
			(layer "B.SilkS")
		)
		(fp_line
			(start -0.7874 0.4064)
			(end 0.7874 0.4064)
			(stroke
				(width 0.1524)
				(type default)
			)
			(layer "B.SilkS")
		)
		(fp_line
			(start -0.7874 -0.4064)
			(end -0.7874 0.4064)
			(stroke
				(width 0.1524)
				(type default)
			)
			(layer "B.SilkS")
		)
		(fp_line
			(start 0.67945 0.3048)
			(end 0.67945 -0.305054)
			(stroke
				(width 0.1)
				(type default)
			)
			(layer "B.Fab")
		)
		(fp_line
			(start 0.67945 -0.305054)
			(end 0.12065 -0.305054)
			(stroke
				(width 0.1)
				(type default)
			)
			(layer "B.Fab")
		)
		(fp_line
			(start 0.12065 0.3048)
			(end 0.67945 0.3048)
			(stroke
				(width 0.1)
				(type default)
			)
			(layer "B.Fab")
		)
		(fp_line
			(start 0.12065 0.2794)
			(end 0.12065 0.3048)
			(stroke
				(width 0.1)
				(type default)
			)
			(layer "B.Fab")
		)
		(fp_line
			(start 0.12065 -0.2794)
			(end -0.12065 -0.2794)
			(stroke
				(width 0.1)
				(type default)
			)
			(layer "B.Fab")
		)
		(fp_line
			(start 0.12065 -0.305054)
			(end 0.12065 -0.2794)
			(stroke
				(width 0.1)
				(type default)
			)
			(layer "B.Fab")
		)
		(fp_line
			(start -0.120396 0.3048)
			(end -0.120396 0.2794)
			(stroke
				(width 0.1)
				(type default)
			)
			(layer "B.Fab")
		)
		(fp_line
			(start -0.120396 0.2794)
			(end 0.12065 0.2794)
			(stroke
				(width 0.1)
				(type default)
			)
			(layer "B.Fab")
		)
		(fp_line
			(start -0.12065 -0.2794)
			(end -0.12065 -0.3048)
			(stroke
				(width 0.1)
				(type default)
			)
			(layer "B.Fab")
		)
		(fp_line
			(start -0.12065 -0.3048)
			(end -0.67945 -0.3048)
			(stroke
				(width 0.1)
				(type default)
			)
			(layer "B.Fab")
		)
		(fp_line
			(start -0.67945 0.3048)
			(end -0.120396 0.3048)
			(stroke
				(width 0.1)
				(type default)
			)
			(layer "B.Fab")
		)
		(fp_line
			(start -0.67945 -0.3048)
			(end -0.67945 0.3048)
			(stroke
				(width 0.1)
				(type default)
			)
			(layer "B.Fab")
		)
		(pad "1" smd circle
			(at 0.40005 0)
			(size 0 0)
			(layers "B.Cu" "B.Mask" "B.Paste")
			(net "P3V3_AUX")
		)
		(pad "2" smd circle
			(at -0.40005 0)
			(size 0 0)
			(layers "B.Cu" "B.Mask" "B.Paste")
			(net "GND")
		)
	)
	(footprint ""
		(layer "B.Cu")
		(at 61.980572 -170.657774)
		(property "Reference" "PC437"
			(at 0 0 0)
			(layer "B.SilkS")
			(hide yes)
			(effects
				(font
					(size 1.27 1.27)
				)
				(justify mirror)
			)
		)
		(property "Value" ""
			(at 0 0 0)
			(layer "B.Fab")
			(effects
				(font
					(size 1.27 1.27)
				)
				(justify mirror)
			)
		)
		(duplicate_pad_numbers_are_jumpers no)
		(fp_line
			(start -1.524 -0.762)
			(end -1.524 0.762)
			(stroke
				(width 0.1524)
				(type default)
			)
			(layer "B.SilkS")
		)
		(fp_line
			(start -1.524 0.762)
			(end 1.524 0.762)
			(stroke
				(width 0.1524)
				(type default)
			)
			(layer "B.SilkS")
		)
		(fp_line
			(start 1.524 -0.762)
			(end -1.524 -0.762)
			(stroke
				(width 0.1524)
				(type default)
			)
			(layer "B.SilkS")
		)
		(fp_line
			(start 1.524 0.762)
			(end 1.524 -0.762)
			(stroke
				(width 0.1524)
				(type default)
			)
			(layer "B.SilkS")
		)
		(fp_line
			(start -1.1049 -0.724916)
			(end 1.1049 -0.724916)
			(stroke
				(width 0.1)
				(type default)
			)
			(layer "B.Fab")
		)
		(fp_line
			(start -1.1049 0.724916)
			(end -1.1049 -0.724916)
			(stroke
				(width 0.1)
				(type default)
			)
			(layer "B.Fab")
		)
		(fp_line
			(start 1.1049 -0.724916)
			(end 1.1049 0.724916)
			(stroke
				(width 0.1)
				(type default)
			)
			(layer "B.Fab")
		)
		(fp_line
			(start 1.1049 0.724916)
			(end -1.1049 0.724916)
			(stroke
				(width 0.1)
				(type default)
			)
			(layer "B.Fab")
		)
		(pad "1" smd rect
			(at 0.889 0)
			(size 1.016 1.27)
			(layers "B.Cu" "B.Mask" "B.Paste")
			(net "PVCCFA_EHV_CPU1")
		)
		(pad "2" smd rect
			(at -0.889 0)
			(size 1.016 1.27)
			(layers "B.Cu" "B.Mask" "B.Paste")
			(net "GND")
		)
	)
)
